# T6G (Grand Teton) — schematic netlist excerpt (pin names and nets, part order shuffled) for the footprints in the layout excerpt that follows; sources: Cadence DE-HDL packaged netlist, KiCad conversion of 04192023_DAF0TMB3IC0_F0TG_MB_C_brd_V02_OCP.brd

C140  Q_CAP  0.1UF 25V 10% X7R  pkg 0402  page 99 : A = P3V3_AUX ; B = GND
R1233  Q_RES  5.11K 1% CHIP  pkg 0402LF  page 258 : A = PVDD18_S5_P0 ; B = PVDD18_S5_P0_ADC
C6608  Q_CAP_DIFFBUS  DIFF BUS_0.22UF 6.3V 20% X6S  pkg C0201  page 308 : \1\ = P5E_CPU0_P3_TX_BUF_C_DN<5> ; \2\ = P5E_CPU0_P3_TX_BUF_DN<5>

(kicad_pcb
	(version 20260206)
	(generator "pcbnew")
	(generator_version "10.0")
	(general
		(thickness 1.6)
		(legacy_teardrops no)
	)
	(paper "A4")
	(title_block
		(title "04192023_DAF0TMB3IC0_F0TG_MB_C_brd_V02_OCP.brd")
		(comment 1 "Grand Teton / footprints 7134-7136 of 8354")
	)
	(layers
		(0 "F.Cu" signal "TOP")
		(4 "In1.Cu" signal "GND")
		(6 "In2.Cu" signal "IN1")
		(8 "In3.Cu" signal "GND1")
		(10 "In4.Cu" signal "IN2")
		(12 "In5.Cu" signal "GND2")
		(14 "In6.Cu" signal "IN3")
		(16 "In7.Cu" signal "GND3")
		(18 "In8.Cu" signal "VCC")
		(20 "In9.Cu" signal "VCC1")
		(22 "In10.Cu" signal "GND4")
		(24 "In11.Cu" signal "IN4")
		(26 "In12.Cu" signal "GND5")
		(28 "In13.Cu" signal "IN5")
		(30 "In14.Cu" signal "GND6")
		(32 "In15.Cu" signal "IN6")
		(34 "In16.Cu" signal "GND7")
		(2 "B.Cu" signal "BOTTOM")
		(9 "F.Adhes" user "F.Adhesive")
		(11 "B.Adhes" user "B.Adhesive")
		(13 "F.Paste" user "Package Geometry/Pastemask Top")
		(15 "B.Paste" user "Package Geometry/Pastemask Bottom")
		(5 "F.SilkS" user "Ref Des/Silkscreen Top")
		(7 "B.SilkS" user "Ref Des/Silkscreen Bottom")
		(1 "F.Mask" user "Board Geometry/Soldermask Top")
		(3 "B.Mask" user "Board Geometry/Soldermask Bottom")
		(17 "Dwgs.User" user "User.Drawings")
		(19 "Cmts.User" user "User.Comments")
		(21 "Eco1.User" user "User.Eco1")
		(23 "Eco2.User" user "User.Eco2")
		(25 "Edge.Cuts" user "Board Geometry/Outline")
		(27 "Margin" user)
		(31 "F.CrtYd" user "Package Geometry/Place Bound Top")
		(29 "B.CrtYd" user "Package Geometry/Place Bound Bottom")
		(35 "F.Fab" user "Ref Des/Assembly Top")
		(33 "B.Fab" user "Ref Des/Assembly Bottom")
	)
	(footprint ""
		(layer "B.Cu")
		(at 237.90148 -327.698608)
		(property "Reference" "R1233"
			(at 0 0 0)
			(layer "B.SilkS")
			(hide yes)
			(effects
				(font
					(size 1.27 1.27)
				)
				(justify mirror)
			)
		)
		(property "Value" ""
			(at 0 0 0)
			(layer "B.Fab")
			(effects
				(font
					(size 1.27 1.27)
				)
				(justify mirror)
			)
		)
		(duplicate_pad_numbers_are_jumpers no)
		(fp_line
			(start -0.7874 -0.4064)
			(end -0.7874 0.4064)
			(stroke
				(width 0.1524)
				(type default)
			)
			(layer "B.SilkS")
		)
		(fp_line
			(start -0.7874 0.4064)
			(end 0.7874 0.4064)
			(stroke
				(width 0.1524)
				(type default)
			)
			(layer "B.SilkS")
		)
		(fp_line
			(start 0.7874 -0.4064)
			(end -0.7874 -0.4064)
			(stroke
				(width 0.1524)
				(type default)
			)
			(layer "B.SilkS")
		)
		(fp_line
			(start 0.7874 0.4064)
			(end 0.7874 -0.4064)
			(stroke
				(width 0.1524)
				(type default)
			)
			(layer "B.SilkS")
		)
		(fp_line
			(start -0.67945 -0.3048)
			(end -0.67945 0.3048)
			(stroke
				(width 0.1)
				(type default)
			)
			(layer "B.Fab")
		)
		(fp_line
			(start -0.67945 0.3048)
			(end -0.120396 0.3048)
			(stroke
				(width 0.1)
				(type default)
			)
			(layer "B.Fab")
		)
		(fp_line
			(start -0.12065 -0.3048)
			(end -0.67945 -0.3048)
			(stroke
				(width 0.1)
				(type default)
			)
			(layer "B.Fab")
		)
		(fp_line
			(start -0.12065 -0.2794)
			(end -0.12065 -0.3048)
			(stroke
				(width 0.1)
				(type default)
			)
			(layer "B.Fab")
		)
		(fp_line
			(start -0.120396 0.2794)
			(end 0.12065 0.2794)
			(stroke
				(width 0.1)
				(type default)
			)
			(layer "B.Fab")
		)
		(fp_line
			(start -0.120396 0.3048)
			(end -0.120396 0.2794)
			(stroke
				(width 0.1)
				(type default)
			)
			(layer "B.Fab")
		)
		(fp_line
			(start 0.12065 -0.305054)
			(end 0.12065 -0.2794)
			(stroke
				(width 0.1)
				(type default)
			)
			(layer "B.Fab")
		)
		(fp_line
			(start 0.12065 -0.2794)
			(end -0.12065 -0.2794)
			(stroke
				(width 0.1)
				(type default)
			)
			(layer "B.Fab")
		)
		(fp_line
			(start 0.12065 0.2794)
			(end 0.12065 0.3048)
			(stroke
				(width 0.1)
				(type default)
			)
			(layer "B.Fab")
		)
		(fp_line
			(start 0.12065 0.3048)
			(end 0.67945 0.3048)
			(stroke
				(width 0.1)
				(type default)
			)
			(layer "B.Fab")
		)
		(fp_line
			(start 0.67945 -0.305054)
			(end 0.12065 -0.305054)
			(stroke
				(width 0.1)
				(type default)
			)
			(layer "B.Fab")
		)
		(fp_line
			(start 0.67945 0.3048)
			(end 0.67945 -0.305054)
			(stroke
				(width 0.1)
				(type default)
			)
			(layer "B.Fab")
		)
		(pad "1" smd circle
			(at 0.40005 0 180)
			(size 0 0)
			(layers "B.Cu" "B.Mask" "B.Paste")
			(net "PVDD18_S5_P0")
		)
		(pad "2" smd circle
			(at -0.40005 0 180)
			(size 0 0)
			(layers "B.Cu" "B.Mask" "B.Paste")
			(net "PVDD18_S5_P0_ADC")
		)
	)
	(footprint ""
		(layer "B.Cu")
		(at 51.120548 -193.996564)
		(property "Reference" "C140"
			(at 0 0 0)
			(layer "B.SilkS")
			(hide yes)
			(effects
				(font
					(size 1.27 1.27)
				)
				(justify mirror)
			)
		)
		(property "Value" ""
			(at 0 0 0)
			(layer "B.Fab")
			(effects
				(font
					(size 1.27 1.27)
				)
				(justify mirror)
			)
		)
		(duplicate_pad_numbers_are_jumpers no)
		(fp_line
			(start -0.7874 -0.4064)
			(end -0.7874 0.4064)
			(stroke
				(width 0.1524)
				(type default)
			)
			(layer "B.SilkS")
		)
		(fp_line
			(start -0.7874 0.4064)
			(end 0.7874 0.4064)
			(stroke
				(width 0.1524)
				(type default)
			)
			(layer "B.SilkS")
		)
		(fp_line
			(start 0.7874 -0.4064)
			(end -0.7874 -0.4064)
			(stroke
				(width 0.1524)
				(type default)
			)
			(layer "B.SilkS")
		)
		(fp_line
			(start 0.7874 0.4064)
			(end 0.7874 -0.4064)
			(stroke
				(width 0.1524)
				(type default)
			)
			(layer "B.SilkS")
		)
		(fp_line
			(start -0.67945 -0.3048)
			(end -0.67945 0.3048)
			(stroke
				(width 0.1)
				(type default)
			)
			(layer "B.Fab")
		)
		(fp_line
			(start -0.67945 0.3048)
			(end -0.120396 0.3048)
			(stroke
				(width 0.1)
				(type default)
			)
			(layer "B.Fab")
		)
		(fp_line
			(start -0.12065 -0.3048)
			(end -0.67945 -0.3048)
			(stroke
				(width 0.1)
				(type default)
			)
			(layer "B.Fab")
		)
		(fp_line
			(start -0.12065 -0.2794)
			(end -0.12065 -0.3048)
			(stroke
				(width 0.1)
				(type default)
			)
			(layer "B.Fab")
		)
		(fp_line
			(start -0.120396 0.2794)
			(end 0.12065 0.2794)
			(stroke
				(width 0.1)
				(type default)
			)
			(layer "B.Fab")
		)
		(fp_line
			(start -0.120396 0.3048)
			(end -0.120396 0.2794)
			(stroke
				(width 0.1)
				(type default)
			)
			(layer "B.Fab")
		)
		(fp_line
			(start 0.12065 -0.305054)
			(end 0.12065 -0.2794)
			(stroke
				(width 0.1)
				(type default)
			)
			(layer "B.Fab")
		)
		(fp_line
			(start 0.12065 -0.2794)
			(end -0.12065 -0.2794)
			(stroke
				(width 0.1)
				(type default)
			)
			(layer "B.Fab")
		)
		(fp_line
			(start 0.12065 0.2794)
			(end 0.12065 0.3048)
			(stroke
				(width 0.1)
				(type default)
			)
			(layer "B.Fab")
		)
		(fp_line
			(start 0.12065 0.3048)
			(end 0.67945 0.3048)
			(stroke
				(width 0.1)
				(type default)
			)
			(layer "B.Fab")
		)
		(fp_line
			(start 0.67945 -0.305054)
			(end 0.12065 -0.305054)
			(stroke
				(width 0.1)
				(type default)
			)
			(layer "B.Fab")
		)
		(fp_line
			(start 0.67945 0.3048)
			(end 0.67945 -0.305054)
			(stroke
				(width 0.1)
				(type default)
			)
			(layer "B.Fab")
		)
		(pad "1" smd circle
			(at 0.40005 0 180)
			(size 0 0)
			(layers "B.Cu" "B.Mask" "B.Paste")
			(net "P3V3_AUX")
		)
		(pad "2" smd circle
			(at -0.40005 0 180)
			(size 0 0)
			(layers "B.Cu" "B.Mask" "B.Paste")
			(net "GND")
		)
	)
	(footprint ""
		(layer "B.Cu")
		(at 387.716522 -416.899344 90)
		(property "Reference" "C6608"
			(at 0 0 90)
			(layer "B.SilkS")
			(hide yes)
			(effects
				(font
					(size 1.27 1.27)
				)
				(justify mirror)
			)
		)
		(property "Value" ""
			(at 0 0 90)
			(layer "B.Fab")
			(effects
				(font
					(size 1.27 1.27)
				)
				(justify mirror)
			)
		)
		(duplicate_pad_numbers_are_jumpers no)
		(fp_line
			(start 0.299974 -0.150114)
			(end -0.299974 -0.150114)
			(stroke
				(width 0.1)
				(type default)
			)
			(layer "B.Fab")
		)
		(fp_line
			(start -0.299974 -0.150114)
			(end -0.299974 0.150114)
			(stroke
				(width 0.1)
				(type default)
			)
			(layer "B.Fab")
		)
		(fp_line
			(start 0.299974 0.150114)
			(end 0.299974 -0.150114)
			(stroke
				(width 0.1)
				(type default)
			)
			(layer "B.Fab")
		)
		(fp_line
			(start -0.299974 0.150114)
			(end 0.299974 0.150114)
			(stroke
				(width 0.1)
				(type default)
			)
			(layer "B.Fab")
		)
		(pad "1" smd rect
			(at 0.2667 0 270)
			(size 0.3048 0.381)
			(layers "B.Cu" "B.Mask" "B.Paste")
			(net "P5E_CPU0_P3_TX_BUF_C_DN<5>")
		)
		(pad "2" smd rect
			(at -0.2667 0 270)
			(size 0.3048 0.381)
			(layers "B.Cu" "B.Mask" "B.Paste")
			(net "P5E_CPU0_P3_TX_BUF_DN<5>")
		)
	)
)
